(kicad_pcb
	(version 20260206)
	(generator "pcbnew")
	(generator_version "10.0")
	(general
		(thickness 1.6)
		(legacy_teardrops no)
	)
	(paper "A4")
	(title_block
		(title "04192023_DAF0TMB3IC0_F0TG_MB_C_brd_V02_OCP.brd")
		(comment 1 "Grand Teton / footprints 7690-7696 of 8354")
	)
	(layers
		(0 "F.Cu" signal "TOP")
		(4 "In1.Cu" signal "GND")
		(6 "In2.Cu" signal "IN1")
		(8 "In3.Cu" signal "GND1")
		(10 "In4.Cu" signal "IN2")
		(12 "In5.Cu" signal "GND2")
		(14 "In6.Cu" signal "IN3")
		(16 "In7.Cu" signal "GND3")
		(18 "In8.Cu" signal "VCC")
		(20 "In9.Cu" signal "VCC1")
		(22 "In10.Cu" signal "GND4")
		(24 "In11.Cu" signal "IN4")
		(26 "In12.Cu" signal "GND5")
		(28 "In13.Cu" signal "IN5")
		(30 "In14.Cu" signal "GND6")
		(32 "In15.Cu" signal "IN6")
		(34 "In16.Cu" signal "GND7")
		(2 "B.Cu" signal "BOTTOM")
		(9 "F.Adhes" user "F.Adhesive")
		(11 "B.Adhes" user "B.Adhesive")
		(13 "F.Paste" user "Package Geometry/Pastemask Top")
		(15 "B.Paste" user "Package Geometry/Pastemask Bottom")
		(5 "F.SilkS" user "Ref Des/Silkscreen Top")
		(7 "B.SilkS" user "Ref Des/Silkscreen Bottom")
		(1 "F.Mask" user "Board Geometry/Soldermask Top")
		(3 "B.Mask" user "Board Geometry/Soldermask Bottom")
		(17 "Dwgs.User" user "User.Drawings")
		(19 "Cmts.User" user "User.Comments")
		(21 "Eco1.User" user "User.Eco1")
		(23 "Eco2.User" user "User.Eco2")
		(25 "Edge.Cuts" user "Board Geometry/Outline")
		(27 "Margin" user)
		(31 "F.CrtYd" user "Package Geometry/Place Bound Top")
		(29 "B.CrtYd" user "Package Geometry/Place Bound Bottom")
		(35 "F.Fab" user "Ref Des/Assembly Top")
		(33 "B.Fab" user "Ref Des/Assembly Bottom")
	)
	(footprint ""
		(layer "B.Cu")
		(at 103.672386 -262.703564 180)
		(property "Reference" "C2416"
			(at 0 0 0)
			(layer "B.SilkS")
			(hide yes)
			(effects
				(font
					(size 1.27 1.27)
				)
				(justify mirror)
			)
		)
		(property "Value" ""
			(at 0 0 0)
			(layer "B.Fab")
			(effects
				(font
					(size 1.27 1.27)
				)
				(justify mirror)
			)
		)
		(duplicate_pad_numbers_are_jumpers no)
		(fp_line
			(start 0.7874 0.4064)
			(end 0.7874 -0.4064)
			(stroke
				(width 0.1524)
				(type default)
			)
			(layer "B.SilkS")
		)
		(fp_line
			(start 0.7874 -0.4064)
			(end -0.7874 -0.4064)
			(stroke
				(width 0.1524)
				(type default)
			)
			(layer "B.SilkS")
		)
		(fp_line
			(start -0.7874 0.4064)
			(end 0.7874 0.4064)
			(stroke
				(width 0.1524)
				(type default)
			)
			(layer "B.SilkS")
		)
		(fp_line
			(start -0.7874 -0.4064)
			(end -0.7874 0.4064)
			(stroke
				(width 0.1524)
				(type default)
			)
			(layer "B.SilkS")
		)
		(fp_line
			(start 0.67945 0.3048)
			(end 0.67945 -0.305054)
			(stroke
				(width 0.1)
				(type default)
			)
			(layer "B.Fab")
		)
		(fp_line
			(start 0.67945 -0.305054)
			(end 0.12065 -0.305054)
			(stroke
				(width 0.1)
				(type default)
			)
			(layer "B.Fab")
		)
		(fp_line
			(start 0.12065 0.3048)
			(end 0.67945 0.3048)
			(stroke
				(width 0.1)
				(type default)
			)
			(layer "B.Fab")
		)
		(fp_line
			(start 0.12065 0.2794)
			(end 0.12065 0.3048)
			(stroke
				(width 0.1)
				(type default)
			)
			(layer "B.Fab")
		)
		(fp_line
			(start 0.12065 -0.2794)
			(end -0.12065 -0.2794)
			(stroke
				(width 0.1)
				(type default)
			)
			(layer "B.Fab")
		)
		(fp_line
			(start 0.12065 -0.305054)
			(end 0.12065 -0.2794)
			(stroke
				(width 0.1)
				(type default)
			)
			(layer "B.Fab")
		)
		(fp_line
			(start -0.120396 0.3048)
			(end -0.120396 0.2794)
			(stroke
				(width 0.1)
				(type default)
			)
			(layer "B.Fab")
		)
		(fp_line
			(start -0.120396 0.2794)
			(end 0.12065 0.2794)
			(stroke
				(width 0.1)
				(type default)
			)
			(layer "B.Fab")
		)
		(fp_line
			(start -0.12065 -0.2794)
			(end -0.12065 -0.3048)
			(stroke
				(width 0.1)
				(type default)
			)
			(layer "B.Fab")
		)
		(fp_line
			(start -0.12065 -0.3048)
			(end -0.67945 -0.3048)
			(stroke
				(width 0.1)
				(type default)
			)
			(layer "B.Fab")
		)
		(fp_line
			(start -0.67945 0.3048)
			(end -0.120396 0.3048)
			(stroke
				(width 0.1)
				(type default)
			)
			(layer "B.Fab")
		)
		(fp_line
			(start -0.67945 -0.3048)
			(end -0.67945 0.3048)
			(stroke
				(width 0.1)
				(type default)
			)
			(layer "B.Fab")
		)
		(pad "1" smd circle
			(at 0.40005 0)
			(size 0 0)
			(layers "B.Cu" "B.Mask" "B.Paste")
			(net "PVDDCR_SOC_P1")
		)
		(pad "2" smd circle
			(at -0.40005 0)
			(size 0 0)
			(layers "B.Cu" "B.Mask" "B.Paste")
			(net "GND")
		)
	)
	(footprint ""
		(layer "B.Cu")
		(at 101.894386 -261.179564)
		(property "Reference" "C2440"
			(at 0 0 0)
			(layer "B.SilkS")
			(hide yes)
			(effects
				(font
					(size 1.27 1.27)
				)
				(justify mirror)
			)
		)
		(property "Value" ""
			(at 0 0 0)
			(layer "B.Fab")
			(effects
				(font
					(size 1.27 1.27)
				)
				(justify mirror)
			)
		)
		(duplicate_pad_numbers_are_jumpers no)
		(fp_line
			(start -0.7874 -0.4064)
			(end -0.7874 0.4064)
			(stroke
				(width 0.1524)
				(type default)
			)
			(layer "B.SilkS")
		)
		(fp_line
			(start -0.7874 0.4064)
			(end 0.7874 0.4064)
			(stroke
				(width 0.1524)
				(type default)
			)
			(layer "B.SilkS")
		)
		(fp_line
			(start 0.7874 -0.4064)
			(end -0.7874 -0.4064)
			(stroke
				(width 0.1524)
				(type default)
			)
			(layer "B.SilkS")
		)
		(fp_line
			(start 0.7874 0.4064)
			(end 0.7874 -0.4064)
			(stroke
				(width 0.1524)
				(type default)
			)
			(layer "B.SilkS")
		)
		(fp_line
			(start -0.67945 -0.3048)
			(end -0.67945 0.3048)
			(stroke
				(width 0.1)
				(type default)
			)
			(layer "B.Fab")
		)
		(fp_line
			(start -0.67945 0.3048)
			(end -0.120396 0.3048)
			(stroke
				(width 0.1)
				(type default)
			)
			(layer "B.Fab")
		)
		(fp_line
			(start -0.12065 -0.3048)
			(end -0.67945 -0.3048)
			(stroke
				(width 0.1)
				(type default)
			)
			(layer "B.Fab")
		)
		(fp_line
			(start -0.12065 -0.2794)
			(end -0.12065 -0.3048)
			(stroke
				(width 0.1)
				(type default)
			)
			(layer "B.Fab")
		)
		(fp_line
			(start -0.120396 0.2794)
			(end 0.12065 0.2794)
			(stroke
				(width 0.1)
				(type default)
			)
			(layer "B.Fab")
		)
		(fp_line
			(start -0.120396 0.3048)
			(end -0.120396 0.2794)
			(stroke
				(width 0.1)
				(type default)
			)
			(layer "B.Fab")
		)
		(fp_line
			(start 0.12065 -0.305054)
			(end 0.12065 -0.2794)
			(stroke
				(width 0.1)
				(type default)
			)
			(layer "B.Fab")
		)
		(fp_line
			(start 0.12065 -0.2794)
			(end -0.12065 -0.2794)
			(stroke
				(width 0.1)
				(type default)
			)
			(layer "B.Fab")
		)
		(fp_line
			(start 0.12065 0.2794)
			(end 0.12065 0.3048)
			(stroke
				(width 0.1)
				(type default)
			)
			(layer "B.Fab")
		)
		(fp_line
			(start 0.12065 0.3048)
			(end 0.67945 0.3048)
			(stroke
				(width 0.1)
				(type default)
			)
			(layer "B.Fab")
		)
		(fp_line
			(start 0.67945 -0.305054)
			(end 0.12065 -0.305054)
			(stroke
				(width 0.1)
				(type default)
			)
			(layer "B.Fab")
		)
		(fp_line
			(start 0.67945 0.3048)
			(end 0.67945 -0.305054)
			(stroke
				(width 0.1)
				(type default)
			)
			(layer "B.Fab")
		)
		(pad "1" smd circle
			(at 0.40005 0 180)
			(size 0 0)
			(layers "B.Cu" "B.Mask" "B.Paste")
			(net "PVDDCR_SOC_P1")
		)
		(pad "2" smd circle
			(at -0.40005 0 180)
			(size 0 0)
			(layers "B.Cu" "B.Mask" "B.Paste")
			(net "GND")
		)
	)
	(footprint ""
		(layer "B.Cu")
		(at 166.24046 -190.821564)
		(property "Reference" "R109"
			(at 0 0 0)
			(layer "B.SilkS")
			(hide yes)
			(effects
				(font
					(size 1.27 1.27)
				)
				(justify mirror)
			)
		)
		(property "Value" ""
			(at 0 0 0)
			(layer "B.Fab")
			(effects
				(font
					(size 1.27 1.27)
				)
				(justify mirror)
			)
		)
		(duplicate_pad_numbers_are_jumpers no)
		(fp_line
			(start -0.7874 -0.4064)
			(end -0.7874 0.4064)
			(stroke
				(width 0.1524)
				(type default)
			)
			(layer "B.SilkS")
		)
		(fp_line
			(start -0.7874 0.4064)
			(end 0.7874 0.4064)
			(stroke
				(width 0.1524)
				(type default)
			)
			(layer "B.SilkS")
		)
		(fp_line
			(start 0.7874 -0.4064)
			(end -0.7874 -0.4064)
			(stroke
				(width 0.1524)
				(type default)
			)
			(layer "B.SilkS")
		)
		(fp_line
			(start 0.7874 0.4064)
			(end 0.7874 -0.4064)
			(stroke
				(width 0.1524)
				(type default)
			)
			(layer "B.SilkS")
		)
		(fp_line
			(start -0.67945 -0.3048)
			(end -0.67945 0.3048)
			(stroke
				(width 0.1)
				(type default)
			)
			(layer "B.Fab")
		)
		(fp_line
			(start -0.67945 0.3048)
			(end -0.120396 0.3048)
			(stroke
				(width 0.1)
				(type default)
			)
			(layer "B.Fab")
		)
		(fp_line
			(start -0.12065 -0.3048)
			(end -0.67945 -0.3048)
			(stroke
				(width 0.1)
				(type default)
			)
			(layer "B.Fab")
		)
		(fp_line
			(start -0.12065 -0.2794)
			(end -0.12065 -0.3048)
			(stroke
				(width 0.1)
				(type default)
			)
			(layer "B.Fab")
		)
		(fp_line
			(start -0.120396 0.2794)
			(end 0.12065 0.2794)
			(stroke
				(width 0.1)
				(type default)
			)
			(layer "B.Fab")
		)
		(fp_line
			(start -0.120396 0.3048)
			(end -0.120396 0.2794)
			(stroke
				(width 0.1)
				(type default)
			)
			(layer "B.Fab")
		)
		(fp_line
			(start 0.12065 -0.305054)
			(end 0.12065 -0.2794)
			(stroke
				(width 0.1)
				(type default)
			)
			(layer "B.Fab")
		)
		(fp_line
			(start 0.12065 -0.2794)
			(end -0.12065 -0.2794)
			(stroke
				(width 0.1)
				(type default)
			)
			(layer "B.Fab")
		)
		(fp_line
			(start 0.12065 0.2794)
			(end 0.12065 0.3048)
			(stroke
				(width 0.1)
				(type default)
			)
			(layer "B.Fab")
		)
		(fp_line
			(start 0.12065 0.3048)
			(end 0.67945 0.3048)
			(stroke
				(width 0.1)
				(type default)
			)
			(layer "B.Fab")
		)
		(fp_line
			(start 0.67945 -0.305054)
			(end 0.12065 -0.305054)
			(stroke
				(width 0.1)
				(type default)
			)
			(layer "B.Fab")
		)
		(fp_line
			(start 0.67945 0.3048)
			(end 0.67945 -0.305054)
			(stroke
				(width 0.1)
				(type default)
			)
			(layer "B.Fab")
		)
		(pad "1" smd circle
			(at 0.40005 0 180)
			(size 0 0)
			(layers "B.Cu" "B.Mask" "B.Paste")
			(net "P3V3")
		)
		(pad "2" smd circle
			(at -0.40005 0 180)
			(size 0 0)
			(layers "B.Cu" "B.Mask" "B.Paste")
			(net "PWRGD_CHGL_CPU1")
		)
	)
	(footprint ""
		(layer "B.Cu")
		(at 232.156 -240.03 180)
		(property "Reference" "R142"
			(at 0 0 0)
			(layer "B.SilkS")
			(hide yes)
			(effects
				(font
					(size 1.27 1.27)
				)
				(justify mirror)
			)
		)
		(property "Value" ""
			(at 0 0 0)
			(layer "B.Fab")
			(effects
				(font
					(size 1.27 1.27)
				)
				(justify mirror)
			)
		)
		(duplicate_pad_numbers_are_jumpers no)
		(fp_line
			(start 0.7874 0.4064)
			(end 0.7874 -0.4064)
			(stroke
				(width 0.1524)
				(type default)
			)
			(layer "B.SilkS")
		)
		(fp_line
			(start 0.7874 -0.4064)
			(end -0.7874 -0.4064)
			(stroke
				(width 0.1524)
				(type default)
			)
			(layer "B.SilkS")
		)
		(fp_line
			(start -0.7874 0.4064)
			(end 0.7874 0.4064)
			(stroke
				(width 0.1524)
				(type default)
			)
			(layer "B.SilkS")
		)
		(fp_line
			(start -0.7874 -0.4064)
			(end -0.7874 0.4064)
			(stroke
				(width 0.1524)
				(type default)
			)
			(layer "B.SilkS")
		)
		(fp_line
			(start 0.67945 0.3048)
			(end 0.67945 -0.305054)
			(stroke
				(width 0.1)
				(type default)
			)
			(layer "B.Fab")
		)
		(fp_line
			(start 0.67945 -0.305054)
			(end 0.12065 -0.305054)
			(stroke
				(width 0.1)
				(type default)
			)
			(layer "B.Fab")
		)
		(fp_line
			(start 0.12065 0.3048)
			(end 0.67945 0.3048)
			(stroke
				(width 0.1)
				(type default)
			)
			(layer "B.Fab")
		)
		(fp_line
			(start 0.12065 0.2794)
			(end 0.12065 0.3048)
			(stroke
				(width 0.1)
				(type default)
			)
			(layer "B.Fab")
		)
		(fp_line
			(start 0.12065 -0.2794)
			(end -0.12065 -0.2794)
			(stroke
				(width 0.1)
				(type default)
			)
			(layer "B.Fab")
		)
		(fp_line
			(start 0.12065 -0.305054)
			(end 0.12065 -0.2794)
			(stroke
				(width 0.1)
				(type default)
			)
			(layer "B.Fab")
		)
		(fp_line
			(start -0.120396 0.3048)
			(end -0.120396 0.2794)
			(stroke
				(width 0.1)
				(type default)
			)
			(layer "B.Fab")
		)
		(fp_line
			(start -0.120396 0.2794)
			(end 0.12065 0.2794)
			(stroke
				(width 0.1)
				(type default)
			)
			(layer "B.Fab")
		)
		(fp_line
			(start -0.12065 -0.2794)
			(end -0.12065 -0.3048)
			(stroke
				(width 0.1)
				(type default)
			)
			(layer "B.Fab")
		)
		(fp_line
			(start -0.12065 -0.3048)
			(end -0.67945 -0.3048)
			(stroke
				(width 0.1)
				(type default)
			)
			(layer "B.Fab")
		)
		(fp_line
			(start -0.67945 0.3048)
			(end -0.120396 0.3048)
			(stroke
				(width 0.1)
				(type default)
			)
			(layer "B.Fab")
		)
		(fp_line
			(start -0.67945 -0.3048)
			(end -0.67945 0.3048)
			(stroke
				(width 0.1)
				(type default)
			)
			(layer "B.Fab")
		)
		(pad "1" smd circle
			(at 0.40005 0)
			(size 0 0)
			(layers "B.Cu" "B.Mask" "B.Paste")
			(net "SMB_CPU0_CPU1_APML_MUX1_SCL")
		)
		(pad "2" smd circle
			(at -0.40005 0)
			(size 0 0)
			(layers "B.Cu" "B.Mask" "B.Paste")
			(net "SMB_APML_CPU0_R_SCL")
		)
	)
	(footprint ""
		(layer "B.Cu")
		(at 169.66692 -51.399948 180)
		(property "Reference" "C1925"
			(at 0 0 0)
			(layer "B.SilkS")
			(hide yes)
			(effects
				(font
					(size 1.27 1.27)
				)
				(justify mirror)
			)
		)
		(property "Value" ""
			(at 0 0 0)
			(layer "B.Fab")
			(effects
				(font
					(size 1.27 1.27)
				)
				(justify mirror)
			)
		)
		(duplicate_pad_numbers_are_jumpers no)
		(fp_line
			(start 0.7874 0.4064)
			(end 0.7874 -0.4064)
			(stroke
				(width 0.1524)
				(type default)
			)
			(layer "B.SilkS")
		)
		(fp_line
			(start 0.7874 -0.4064)
			(end -0.7874 -0.4064)
			(stroke
				(width 0.1524)
				(type default)
			)
			(layer "B.SilkS")
		)
		(fp_line
			(start -0.7874 0.4064)
			(end 0.7874 0.4064)
			(stroke
				(width 0.1524)
				(type default)
			)
			(layer "B.SilkS")
		)
		(fp_line
			(start -0.7874 -0.4064)
			(end -0.7874 0.4064)
			(stroke
				(width 0.1524)
				(type default)
			)
			(layer "B.SilkS")
		)
		(fp_line
			(start 0.67945 0.3048)
			(end 0.67945 -0.305054)
			(stroke
				(width 0.1)
				(type default)
			)
			(layer "B.Fab")
		)
		(fp_line
			(start 0.67945 -0.305054)
			(end 0.12065 -0.305054)
			(stroke
				(width 0.1)
				(type default)
			)
			(layer "B.Fab")
		)
		(fp_line
			(start 0.12065 0.3048)
			(end 0.67945 0.3048)
			(stroke
				(width 0.1)
				(type default)
			)
			(layer "B.Fab")
		)
		(fp_line
			(start 0.12065 0.2794)
			(end 0.12065 0.3048)
			(stroke
				(width 0.1)
				(type default)
			)
			(layer "B.Fab")
		)
		(fp_line
			(start 0.12065 -0.2794)
			(end -0.12065 -0.2794)
			(stroke
				(width 0.1)
				(type default)
			)
			(layer "B.Fab")
		)
		(fp_line
			(start 0.12065 -0.305054)
			(end 0.12065 -0.2794)
			(stroke
				(width 0.1)
				(type default)
			)
			(layer "B.Fab")
		)
		(fp_line
			(start -0.120396 0.3048)
			(end -0.120396 0.2794)
			(stroke
				(width 0.1)
				(type default)
			)
			(layer "B.Fab")
		)
		(fp_line
			(start -0.120396 0.2794)
			(end 0.12065 0.2794)
			(stroke
				(width 0.1)
				(type default)
			)
			(layer "B.Fab")
		)
		(fp_line
			(start -0.12065 -0.2794)
			(end -0.12065 -0.3048)
			(stroke
				(width 0.1)
				(type default)
			)
			(layer "B.Fab")
		)
		(fp_line
			(start -0.12065 -0.3048)
			(end -0.67945 -0.3048)
			(stroke
				(width 0.1)
				(type default)
			)
			(layer "B.Fab")
		)
		(fp_line
			(start -0.67945 0.3048)
			(end -0.120396 0.3048)
			(stroke
				(width 0.1)
				(type default)
			)
			(layer "B.Fab")
		)
		(fp_line
			(start -0.67945 -0.3048)
			(end -0.67945 0.3048)
			(stroke
				(width 0.1)
				(type default)
			)
			(layer "B.Fab")
		)
		(pad "1" smd circle
			(at 0.40005 0)
			(size 0 0)
			(layers "B.Cu" "B.Mask" "B.Paste")
			(net "P3V3_M2_0")
		)
		(pad "2" smd circle
			(at -0.40005 0)
			(size 0 0)
			(layers "B.Cu" "B.Mask" "B.Paste")
			(net "GND")
		)
	)
	(footprint ""
		(layer "B.Cu")
		(at 237.617 -248.285)
		(property "Reference" "R1155"
			(at 0 0 0)
			(layer "B.SilkS")
			(hide yes)
			(effects
				(font
					(size 1.27 1.27)
				)
				(justify mirror)
			)
		)
		(property "Value" ""
			(at 0 0 0)
			(layer "B.Fab")
			(effects
				(font
					(size 1.27 1.27)
				)
				(justify mirror)
			)
		)
		(duplicate_pad_numbers_are_jumpers no)
		(fp_line
			(start -0.7874 -0.4064)
			(end -0.7874 0.4064)
			(stroke
				(width 0.1524)
				(type default)
			)
			(layer "B.SilkS")
		)
		(fp_line
			(start -0.7874 0.4064)
			(end 0.7874 0.4064)
			(stroke
				(width 0.1524)
				(type default)
			)
			(layer "B.SilkS")
		)
		(fp_line
			(start 0.7874 -0.4064)
			(end -0.7874 -0.4064)
			(stroke
				(width 0.1524)
				(type default)
			)
			(layer "B.SilkS")
		)
		(fp_line
			(start 0.7874 0.4064)
			(end 0.7874 -0.4064)
			(stroke
				(width 0.1524)
				(type default)
			)
			(layer "B.SilkS")
		)
		(fp_line
			(start -0.67945 -0.3048)
			(end -0.67945 0.3048)
			(stroke
				(width 0.1)
				(type default)
			)
			(layer "B.Fab")
		)
		(fp_line
			(start -0.67945 0.3048)
			(end -0.120396 0.3048)
			(stroke
				(width 0.1)
				(type default)
			)
			(layer "B.Fab")
		)
		(fp_line
			(start -0.12065 -0.3048)
			(end -0.67945 -0.3048)
			(stroke
				(width 0.1)
				(type default)
			)
			(layer "B.Fab")
		)
		(fp_line
			(start -0.12065 -0.2794)
			(end -0.12065 -0.3048)
			(stroke
				(width 0.1)
				(type default)
			)
			(layer "B.Fab")
		)
		(fp_line
			(start -0.120396 0.2794)
			(end 0.12065 0.2794)
			(stroke
				(width 0.1)
				(type default)
			)
			(layer "B.Fab")
		)
		(fp_line
			(start -0.120396 0.3048)
			(end -0.120396 0.2794)
			(stroke
				(width 0.1)
				(type default)
			)
			(layer "B.Fab")
		)
		(fp_line
			(start 0.12065 -0.305054)
			(end 0.12065 -0.2794)
			(stroke
				(width 0.1)
				(type default)
			)
			(layer "B.Fab")
		)
		(fp_line
			(start 0.12065 -0.2794)
			(end -0.12065 -0.2794)
			(stroke
				(width 0.1)
				(type default)
			)
			(layer "B.Fab")
		)
		(fp_line
			(start 0.12065 0.2794)
			(end 0.12065 0.3048)
			(stroke
				(width 0.1)
				(type default)
			)
			(layer "B.Fab")
		)
		(fp_line
			(start 0.12065 0.3048)
			(end 0.67945 0.3048)
			(stroke
				(width 0.1)
				(type default)
			)
			(layer "B.Fab")
		)
		(fp_line
			(start 0.67945 -0.305054)
			(end 0.12065 -0.305054)
			(stroke
				(width 0.1)
				(type default)
			)
			(layer "B.Fab")
		)
		(fp_line
			(start 0.67945 0.3048)
			(end 0.67945 -0.305054)
			(stroke
				(width 0.1)
				(type default)
			)
			(layer "B.Fab")
		)
		(pad "1" smd rect
			(at 0.40005 0)
			(size 0.4572 0.508)
			(layers "B.Cu" "B.Mask" "B.Paste")
			(net "SMB_APML_CPU0_R_SDA")
		)
		(pad "2" smd rect
			(at -0.40005 0)
			(size 0.4572 0.508)
			(layers "B.Cu" "B.Mask" "B.Paste")
			(net "SMB_APML_CPU0_SDA")
		)
	)
	(footprint ""
		(layer "B.Cu")
		(at 170.424348 -423.799 90)
		(property "Reference" "C1066"
			(at 0 0 90)
			(layer "B.SilkS")
			(hide yes)
			(effects
				(font
					(size 1.27 1.27)
				)
				(justify mirror)
			)
		)
		(property "Value" ""
			(at 0 0 90)
			(layer "B.Fab")
			(effects
				(font
					(size 1.27 1.27)
				)
				(justify mirror)
			)
		)
		(duplicate_pad_numbers_are_jumpers no)
		(fp_line
			(start 0.299974 -0.150114)
			(end -0.299974 -0.150114)
			(stroke
				(width 0.1)
				(type default)
			)
			(layer "B.Fab")
		)
		(fp_line
			(start -0.299974 -0.150114)
			(end -0.299974 0.150114)
			(stroke
				(width 0.1)
				(type default)
			)
			(layer "B.Fab")
		)
		(fp_line
			(start 0.299974 0.150114)
			(end 0.299974 -0.150114)
			(stroke
				(width 0.1)
				(type default)
			)
			(layer "B.Fab")
		)
		(fp_line
			(start -0.299974 0.150114)
			(end 0.299974 0.150114)
			(stroke
				(width 0.1)
				(type default)
			)
			(layer "B.Fab")
		)
		(pad "1" smd rect
			(at 0.2667 0 270)
			(size 0.3048 0.381)
			(layers "B.Cu" "B.Mask" "B.Paste")
			(net "P3V3_AUX")
		)
		(pad "2" smd rect
			(at -0.2667 0 270)
			(size 0.3048 0.381)
			(layers "B.Cu" "B.Mask" "B.Paste")
			(net "GND")
		)
	)
)
